(kicad_pcb
	(version 20260206)
	(generator "pcbnew")
	(generator_version "10.0")
	(general
		(thickness 1.6)
		(legacy_teardrops no)
	)
	(paper "A4")
	(title_block
		(title "12092022_DA0F0TMDCD0_F0T_Management_Board_D_brd_V3_OCP.brd")
		(comment 1 "Grand Teton / footprints 7-12 of 1440")
	)
	(layers
		(0 "F.Cu" signal "TOP")
		(4 "In1.Cu" signal "GND")
		(6 "In2.Cu" signal "IN1")
		(8 "In3.Cu" signal "GND1")
		(10 "In4.Cu" signal "IN2")
		(12 "In5.Cu" signal "VCC")
		(14 "In6.Cu" signal "VCC1")
		(16 "In7.Cu" signal "IN3")
		(18 "In8.Cu" signal "GND2")
		(20 "In9.Cu" signal "IN4")
		(22 "In10.Cu" signal "GND3")
		(2 "B.Cu" signal "BOTTOM")
		(9 "F.Adhes" user "F.Adhesive")
		(11 "B.Adhes" user "B.Adhesive")
		(13 "F.Paste" user "Package Geometry/Pastemask Top")
		(15 "B.Paste" user "Package Geometry/Pastemask Bottom")
		(5 "F.SilkS" user "Ref Des/Silkscreen Top")
		(7 "B.SilkS" user "Ref Des/Silkscreen Bottom")
		(1 "F.Mask" user "Board Geometry/Soldermask Top")
		(3 "B.Mask" user "Board Geometry/Soldermask Bottom")
		(17 "Dwgs.User" user "User.Drawings")
		(19 "Cmts.User" user "User.Comments")
		(21 "Eco1.User" user "User.Eco1")
		(23 "Eco2.User" user "User.Eco2")
		(25 "Edge.Cuts" user "Board Geometry/Outline")
		(27 "Margin" user)
		(31 "F.CrtYd" user "Package Geometry/Place Bound Top")
		(29 "B.CrtYd" user "Package Geometry/Place Bound Bottom")
		(35 "F.Fab" user "Ref Des/Assembly Top")
		(33 "B.Fab" user "Ref Des/Assembly Bottom")
	)
	(footprint ""
		(layer "F.Cu")
		(at 36.8808 -109.4613 -90)
		(property "Reference" "R74"
			(at 0 0 270)
			(layer "F.SilkS")
			(hide yes)
			(effects
				(font
					(size 1.27 1.27)
				)
			)
		)
		(property "Value" ""
			(at 0 0 270)
			(layer "F.Fab")
			(effects
				(font
					(size 1.27 1.27)
				)
			)
		)
		(duplicate_pad_numbers_are_jumpers no)
		(fp_line
			(start -0.7874 0.4064)
			(end -0.7874 -0.4064)
			(stroke
				(width 0.1524)
				(type default)
			)
			(layer "F.SilkS")
		)
		(fp_line
			(start 0.7874 0.4064)
			(end -0.7874 0.4064)
			(stroke
				(width 0.1524)
				(type default)
			)
			(layer "F.SilkS")
		)
		(fp_line
			(start -0.7874 -0.4064)
			(end 0.7874 -0.4064)
			(stroke
				(width 0.1524)
				(type default)
			)
			(layer "F.SilkS")
		)
		(fp_line
			(start 0.7874 -0.4064)
			(end 0.7874 0.4064)
			(stroke
				(width 0.1524)
				(type default)
			)
			(layer "F.SilkS")
		)
		(fp_line
			(start -0.67945 0.3048)
			(end -0.67945 -0.305054)
			(stroke
				(width 0.1)
				(type default)
			)
			(layer "F.Fab")
		)
		(fp_line
			(start -0.12065 0.3048)
			(end -0.67945 0.3048)
			(stroke
				(width 0.1)
				(type default)
			)
			(layer "F.Fab")
		)
		(fp_line
			(start 0.120396 0.3048)
			(end 0.120396 0.2794)
			(stroke
				(width 0.1)
				(type default)
			)
			(layer "F.Fab")
		)
		(fp_line
			(start 0.67945 0.3048)
			(end 0.120396 0.3048)
			(stroke
				(width 0.1)
				(type default)
			)
			(layer "F.Fab")
		)
		(fp_line
			(start -0.12065 0.2794)
			(end -0.12065 0.3048)
			(stroke
				(width 0.1)
				(type default)
			)
			(layer "F.Fab")
		)
		(fp_line
			(start 0.120396 0.2794)
			(end -0.12065 0.2794)
			(stroke
				(width 0.1)
				(type default)
			)
			(layer "F.Fab")
		)
		(fp_line
			(start -0.12065 -0.2794)
			(end 0.12065 -0.2794)
			(stroke
				(width 0.1)
				(type default)
			)
			(layer "F.Fab")
		)
		(fp_line
			(start 0.12065 -0.2794)
			(end 0.12065 -0.3048)
			(stroke
				(width 0.1)
				(type default)
			)
			(layer "F.Fab")
		)
		(fp_line
			(start 0.12065 -0.3048)
			(end 0.67945 -0.3048)
			(stroke
				(width 0.1)
				(type default)
			)
			(layer "F.Fab")
		)
		(fp_line
			(start 0.67945 -0.3048)
			(end 0.67945 0.3048)
			(stroke
				(width 0.1)
				(type default)
			)
			(layer "F.Fab")
		)
		(fp_line
			(start -0.67945 -0.305054)
			(end -0.12065 -0.305054)
			(stroke
				(width 0.1)
				(type default)
			)
			(layer "F.Fab")
		)
		(fp_line
			(start -0.12065 -0.305054)
			(end -0.12065 -0.2794)
			(stroke
				(width 0.1)
				(type default)
			)
			(layer "F.Fab")
		)
		(pad "1" smd circle
			(at -0.40005 0 270)
			(size 0 0)
			(layers "F.Cu" "F.Mask" "F.Paste")
			(net "P3V3_AUX")
		)
		(pad "2" smd circle
			(at 0.40005 0 270)
			(size 0 0)
			(layers "F.Cu" "F.Mask" "F.Paste")
			(net "SGPIO_DI_1")
		)
	)
	(footprint ""
		(layer "F.Cu")
		(at 7.4422 -67.183 180)
		(property "Reference" "PC224"
			(at 0 0 180)
			(layer "F.SilkS")
			(hide yes)
			(effects
				(font
					(size 1.27 1.27)
				)
			)
		)
		(property "Value" ""
			(at 0 0 180)
			(layer "F.Fab")
			(effects
				(font
					(size 1.27 1.27)
				)
			)
		)
		(duplicate_pad_numbers_are_jumpers no)
		(fp_line
			(start 0.7874 0.4064)
			(end -0.7874 0.4064)
			(stroke
				(width 0.1524)
				(type default)
			)
			(layer "F.SilkS")
		)
		(fp_line
			(start 0.7874 -0.4064)
			(end 0.7874 0.4064)
			(stroke
				(width 0.1524)
				(type default)
			)
			(layer "F.SilkS")
		)
		(fp_line
			(start -0.7874 0.4064)
			(end -0.7874 -0.4064)
			(stroke
				(width 0.1524)
				(type default)
			)
			(layer "F.SilkS")
		)
		(fp_line
			(start -0.7874 -0.4064)
			(end 0.7874 -0.4064)
			(stroke
				(width 0.1524)
				(type default)
			)
			(layer "F.SilkS")
		)
		(fp_line
			(start 0.67945 0.3048)
			(end 0.120396 0.3048)
			(stroke
				(width 0.1)
				(type default)
			)
			(layer "F.Fab")
		)
		(fp_line
			(start 0.67945 -0.3048)
			(end 0.67945 0.3048)
			(stroke
				(width 0.1)
				(type default)
			)
			(layer "F.Fab")
		)
		(fp_line
			(start 0.12065 -0.2794)
			(end 0.12065 -0.3048)
			(stroke
				(width 0.1)
				(type default)
			)
			(layer "F.Fab")
		)
		(fp_line
			(start 0.12065 -0.3048)
			(end 0.67945 -0.3048)
			(stroke
				(width 0.1)
				(type default)
			)
			(layer "F.Fab")
		)
		(fp_line
			(start 0.120396 0.3048)
			(end 0.120396 0.2794)
			(stroke
				(width 0.1)
				(type default)
			)
			(layer "F.Fab")
		)
		(fp_line
			(start 0.120396 0.2794)
			(end -0.12065 0.2794)
			(stroke
				(width 0.1)
				(type default)
			)
			(layer "F.Fab")
		)
		(fp_line
			(start -0.12065 0.3048)
			(end -0.67945 0.3048)
			(stroke
				(width 0.1)
				(type default)
			)
			(layer "F.Fab")
		)
		(fp_line
			(start -0.12065 0.2794)
			(end -0.12065 0.3048)
			(stroke
				(width 0.1)
				(type default)
			)
			(layer "F.Fab")
		)
		(fp_line
			(start -0.12065 -0.2794)
			(end 0.12065 -0.2794)
			(stroke
				(width 0.1)
				(type default)
			)
			(layer "F.Fab")
		)
		(fp_line
			(start -0.12065 -0.305054)
			(end -0.12065 -0.2794)
			(stroke
				(width 0.1)
				(type default)
			)
			(layer "F.Fab")
		)
		(fp_line
			(start -0.67945 0.3048)
			(end -0.67945 -0.305054)
			(stroke
				(width 0.1)
				(type default)
			)
			(layer "F.Fab")
		)
		(fp_line
			(start -0.67945 -0.305054)
			(end -0.12065 -0.305054)
			(stroke
				(width 0.1)
				(type default)
			)
			(layer "F.Fab")
		)
		(pad "1" smd circle
			(at -0.40005 0 180)
			(size 0 0)
			(layers "F.Cu" "F.Mask" "F.Paste")
			(net "SW_P3V3_AUX_BST")
		)
		(pad "2" smd circle
			(at 0.40005 0 180)
			(size 0 0)
			(layers "F.Cu" "F.Mask" "F.Paste")
			(net "SW_P3V3_AUX_SW")
		)
	)
	(footprint ""
		(layer "F.Cu")
		(at 69.90588 -25.2349 180)
		(property "Reference" "R513"
			(at 0 0 180)
			(layer "F.SilkS")
			(hide yes)
			(effects
				(font
					(size 1.27 1.27)
				)
			)
		)
		(property "Value" ""
			(at 0 0 180)
			(layer "F.Fab")
			(effects
				(font
					(size 1.27 1.27)
				)
			)
		)
		(duplicate_pad_numbers_are_jumpers no)
		(fp_line
			(start 0.7874 0.4064)
			(end -0.7874 0.4064)
			(stroke
				(width 0.1524)
				(type default)
			)
			(layer "F.SilkS")
		)
		(fp_line
			(start 0.7874 -0.4064)
			(end 0.7874 0.4064)
			(stroke
				(width 0.1524)
				(type default)
			)
			(layer "F.SilkS")
		)
		(fp_line
			(start -0.7874 0.4064)
			(end -0.7874 -0.4064)
			(stroke
				(width 0.1524)
				(type default)
			)
			(layer "F.SilkS")
		)
		(fp_line
			(start -0.7874 -0.4064)
			(end 0.7874 -0.4064)
			(stroke
				(width 0.1524)
				(type default)
			)
			(layer "F.SilkS")
		)
		(fp_line
			(start 0.67945 0.3048)
			(end 0.120396 0.3048)
			(stroke
				(width 0.1)
				(type default)
			)
			(layer "F.Fab")
		)
		(fp_line
			(start 0.67945 -0.3048)
			(end 0.67945 0.3048)
			(stroke
				(width 0.1)
				(type default)
			)
			(layer "F.Fab")
		)
		(fp_line
			(start 0.12065 -0.2794)
			(end 0.12065 -0.3048)
			(stroke
				(width 0.1)
				(type default)
			)
			(layer "F.Fab")
		)
		(fp_line
			(start 0.12065 -0.3048)
			(end 0.67945 -0.3048)
			(stroke
				(width 0.1)
				(type default)
			)
			(layer "F.Fab")
		)
		(fp_line
			(start 0.120396 0.3048)
			(end 0.120396 0.2794)
			(stroke
				(width 0.1)
				(type default)
			)
			(layer "F.Fab")
		)
		(fp_line
			(start 0.120396 0.2794)
			(end -0.12065 0.2794)
			(stroke
				(width 0.1)
				(type default)
			)
			(layer "F.Fab")
		)
		(fp_line
			(start -0.12065 0.3048)
			(end -0.67945 0.3048)
			(stroke
				(width 0.1)
				(type default)
			)
			(layer "F.Fab")
		)
		(fp_line
			(start -0.12065 0.2794)
			(end -0.12065 0.3048)
			(stroke
				(width 0.1)
				(type default)
			)
			(layer "F.Fab")
		)
		(fp_line
			(start -0.12065 -0.2794)
			(end 0.12065 -0.2794)
			(stroke
				(width 0.1)
				(type default)
			)
			(layer "F.Fab")
		)
		(fp_line
			(start -0.12065 -0.305054)
			(end -0.12065 -0.2794)
			(stroke
				(width 0.1)
				(type default)
			)
			(layer "F.Fab")
		)
		(fp_line
			(start -0.67945 0.3048)
			(end -0.67945 -0.305054)
			(stroke
				(width 0.1)
				(type default)
			)
			(layer "F.Fab")
		)
		(fp_line
			(start -0.67945 -0.305054)
			(end -0.12065 -0.305054)
			(stroke
				(width 0.1)
				(type default)
			)
			(layer "F.Fab")
		)
		(pad "1" smd circle
			(at -0.40005 0 180)
			(size 0 0)
			(layers "F.Cu" "F.Mask" "F.Paste")
			(net "JTAG_SCM_TDO")
		)
		(pad "2" smd circle
			(at 0.40005 0 180)
			(size 0 0)
			(layers "F.Cu" "F.Mask" "F.Paste")
			(net "JTAG_SCM_PLD_TDO")
		)
	)
	(footprint ""
		(layer "F.Cu")
		(at 73.941686 -37.523674 180)
		(property "Reference" "L8"
			(at 0 0 180)
			(layer "F.SilkS")
			(hide yes)
			(effects
				(font
					(size 1.27 1.27)
				)
			)
		)
		(property "Value" ""
			(at 0 0 180)
			(layer "F.Fab")
			(effects
				(font
					(size 1.27 1.27)
				)
			)
		)
		(duplicate_pad_numbers_are_jumpers no)
		(fp_line
			(start 1.27 0.5842)
			(end 1.27 -0.5842)
			(stroke
				(width 0.1524)
				(type default)
			)
			(layer "F.SilkS")
		)
		(fp_line
			(start 1.27 0.5842)
			(end -1.27 0.5842)
			(stroke
				(width 0.1524)
				(type default)
			)
			(layer "F.SilkS")
		)
		(fp_line
			(start 0.127 0.5842)
			(end 0.127 -0.5842)
			(stroke
				(width 0.1524)
				(type default)
			)
			(layer "F.SilkS")
		)
		(fp_line
			(start -0.127 0.5842)
			(end -0.127 -0.5842)
			(stroke
				(width 0.1524)
				(type default)
			)
			(layer "F.SilkS")
		)
		(fp_line
			(start -1.27 0.5842)
			(end -1.27 -0.5842)
			(stroke
				(width 0.1524)
				(type default)
			)
			(layer "F.SilkS")
		)
		(fp_line
			(start -1.27 -0.5588)
			(end -1.27 -0.5842)
			(stroke
				(width 0.1524)
				(type default)
			)
			(layer "F.SilkS")
		)
		(fp_line
			(start -1.27 -0.5842)
			(end 1.27 -0.5842)
			(stroke
				(width 0.1524)
				(type default)
			)
			(layer "F.SilkS")
		)
		(fp_line
			(start 1.1938 0.4064)
			(end 0.9144 0.4064)
			(stroke
				(width 0.1)
				(type default)
			)
			(layer "F.Fab")
		)
		(fp_line
			(start 1.1938 -0.406654)
			(end 1.1938 0.4064)
			(stroke
				(width 0.1)
				(type default)
			)
			(layer "F.Fab")
		)
		(fp_line
			(start 0.9144 0.508)
			(end -0.9144 0.508)
			(stroke
				(width 0.1)
				(type default)
			)
			(layer "F.Fab")
		)
		(fp_line
			(start 0.9144 0.4064)
			(end 0.9144 0.508)
			(stroke
				(width 0.1)
				(type default)
			)
			(layer "F.Fab")
		)
		(fp_line
			(start 0.9144 -0.406654)
			(end 1.1938 -0.406654)
			(stroke
				(width 0.1)
				(type default)
			)
			(layer "F.Fab")
		)
		(fp_line
			(start 0.9144 -0.508)
			(end 0.9144 -0.406654)
			(stroke
				(width 0.1)
				(type default)
			)
			(layer "F.Fab")
		)
		(fp_line
			(start -0.9144 0.508)
			(end -0.9144 0.406654)
			(stroke
				(width 0.1)
				(type default)
			)
			(layer "F.Fab")
		)
		(fp_line
			(start -0.9144 0.406654)
			(end -1.194308 0.406654)
			(stroke
				(width 0.1)
				(type default)
			)
			(layer "F.Fab")
		)
		(fp_line
			(start -0.9144 -0.406654)
			(end -0.9144 -0.508)
			(stroke
				(width 0.1)
				(type default)
			)
			(layer "F.Fab")
		)
		(fp_line
			(start -0.9144 -0.508)
			(end 0.9144 -0.508)
			(stroke
				(width 0.1)
				(type default)
			)
			(layer "F.Fab")
		)
		(fp_line
			(start -1.194308 0.406654)
			(end -1.194308 -0.406654)
			(stroke
				(width 0.1)
				(type default)
			)
			(layer "F.Fab")
		)
		(fp_line
			(start -1.194308 -0.406654)
			(end -0.9144 -0.406654)
			(stroke
				(width 0.1)
				(type default)
			)
			(layer "F.Fab")
		)
		(pad "1" smd rect
			(at -0.7366 0 90)
			(size 0.7112 0.8128)
			(layers "F.Cu" "F.Mask" "F.Paste")
			(net "P1V0_AUX")
		)
		(pad "2" smd rect
			(at 0.7366 0 90)
			(size 0.7112 0.8128)
			(layers "F.Cu" "F.Mask" "F.Paste")
			(net "P1V0_STBY_PLAVDD")
		)
	)
	(footprint ""
		(layer "F.Cu")
		(at 18.6436 -56.1848 90)
		(property "Reference" "R900"
			(at 0 0 90)
			(layer "F.SilkS")
			(hide yes)
			(effects
				(font
					(size 1.27 1.27)
				)
			)
		)
		(property "Value" ""
			(at 0 0 90)
			(layer "F.Fab")
			(effects
				(font
					(size 1.27 1.27)
				)
			)
		)
		(duplicate_pad_numbers_are_jumpers no)
		(fp_line
			(start 0.7874 -0.4064)
			(end 0.7874 0.4064)
			(stroke
				(width 0.1524)
				(type default)
			)
			(layer "F.SilkS")
		)
		(fp_line
			(start -0.7874 -0.4064)
			(end 0.7874 -0.4064)
			(stroke
				(width 0.1524)
				(type default)
			)
			(layer "F.SilkS")
		)
		(fp_line
			(start 0.7874 0.4064)
			(end -0.7874 0.4064)
			(stroke
				(width 0.1524)
				(type default)
			)
			(layer "F.SilkS")
		)
		(fp_line
			(start -0.7874 0.4064)
			(end -0.7874 -0.4064)
			(stroke
				(width 0.1524)
				(type default)
			)
			(layer "F.SilkS")
		)
		(fp_line
			(start -0.12065 -0.305054)
			(end -0.12065 -0.2794)
			(stroke
				(width 0.1)
				(type default)
			)
			(layer "F.Fab")
		)
		(fp_line
			(start -0.67945 -0.305054)
			(end -0.12065 -0.305054)
			(stroke
				(width 0.1)
				(type default)
			)
			(layer "F.Fab")
		)
		(fp_line
			(start 0.67945 -0.3048)
			(end 0.67945 0.3048)
			(stroke
				(width 0.1)
				(type default)
			)
			(layer "F.Fab")
		)
		(fp_line
			(start 0.12065 -0.3048)
			(end 0.67945 -0.3048)
			(stroke
				(width 0.1)
				(type default)
			)
			(layer "F.Fab")
		)
		(fp_line
			(start 0.12065 -0.2794)
			(end 0.12065 -0.3048)
			(stroke
				(width 0.1)
				(type default)
			)
			(layer "F.Fab")
		)
		(fp_line
			(start -0.12065 -0.2794)
			(end 0.12065 -0.2794)
			(stroke
				(width 0.1)
				(type default)
			)
			(layer "F.Fab")
		)
		(fp_line
			(start 0.120396 0.2794)
			(end -0.12065 0.2794)
			(stroke
				(width 0.1)
				(type default)
			)
			(layer "F.Fab")
		)
		(fp_line
			(start -0.12065 0.2794)
			(end -0.12065 0.3048)
			(stroke
				(width 0.1)
				(type default)
			)
			(layer "F.Fab")
		)
		(fp_line
			(start 0.67945 0.3048)
			(end 0.120396 0.3048)
			(stroke
				(width 0.1)
				(type default)
			)
			(layer "F.Fab")
		)
		(fp_line
			(start 0.120396 0.3048)
			(end 0.120396 0.2794)
			(stroke
				(width 0.1)
				(type default)
			)
			(layer "F.Fab")
		)
		(fp_line
			(start -0.12065 0.3048)
			(end -0.67945 0.3048)
			(stroke
				(width 0.1)
				(type default)
			)
			(layer "F.Fab")
		)
		(fp_line
			(start -0.67945 0.3048)
			(end -0.67945 -0.305054)
			(stroke
				(width 0.1)
				(type default)
			)
			(layer "F.Fab")
		)
		(pad "1" smd circle
			(at -0.40005 0 90)
			(size 0 0)
			(layers "F.Cu" "F.Mask" "F.Paste")
			(net "UART_BIC_DBG_TX")
		)
		(pad "2" smd circle
			(at 0.40005 0 90)
			(size 0 0)
			(layers "F.Cu" "F.Mask" "F.Paste")
			(net "UART_BIC_DBG_TX_R")
		)
	)
	(footprint ""
		(layer "F.Cu")
		(at 63.553848 -34.870898 -90)
		(property "Reference" "R528"
			(at 0 0 270)
			(layer "F.SilkS")
			(hide yes)
			(effects
				(font
					(size 1.27 1.27)
				)
			)
		)
		(property "Value" ""
			(at 0 0 270)
			(layer "F.Fab")
			(effects
				(font
					(size 1.27 1.27)
				)
			)
		)
		(duplicate_pad_numbers_are_jumpers no)
		(fp_line
			(start 0.420878 0.4064)
			(end -0.122682 0.4064)
			(stroke
				(width 0.1524)
				(type default)
			)
			(layer "F.SilkS")
		)
		(fp_line
			(start -0.7874 0.036068)
			(end -0.7874 -0.4064)
			(stroke
				(width 0.1524)
				(type default)
			)
			(layer "F.SilkS")
		)
		(fp_line
			(start -0.7874 -0.4064)
			(end 0.7874 -0.4064)
			(stroke
				(width 0.1524)
				(type default)
			)
			(layer "F.SilkS")
		)
		(fp_line
			(start 0.7874 -0.4064)
			(end 0.7874 0.084328)
			(stroke
				(width 0.1524)
				(type default)
			)
			(layer "F.SilkS")
		)
		(fp_line
			(start -0.67945 0.3048)
			(end -0.67945 -0.305054)
			(stroke
				(width 0.1)
				(type default)
			)
			(layer "F.Fab")
		)
		(fp_line
			(start -0.12065 0.3048)
			(end -0.67945 0.3048)
			(stroke
				(width 0.1)
				(type default)
			)
			(layer "F.Fab")
		)
		(fp_line
			(start 0.120396 0.3048)
			(end 0.120396 0.2794)
			(stroke
				(width 0.1)
				(type default)
			)
			(layer "F.Fab")
		)
		(fp_line
			(start 0.67945 0.3048)
			(end 0.120396 0.3048)
			(stroke
				(width 0.1)
				(type default)
			)
			(layer "F.Fab")
		)
		(fp_line
			(start -0.12065 0.2794)
			(end -0.12065 0.3048)
			(stroke
				(width 0.1)
				(type default)
			)
			(layer "F.Fab")
		)
		(fp_line
			(start 0.120396 0.2794)
			(end -0.12065 0.2794)
			(stroke
				(width 0.1)
				(type default)
			)
			(layer "F.Fab")
		)
		(fp_line
			(start -0.12065 -0.2794)
			(end 0.12065 -0.2794)
			(stroke
				(width 0.1)
				(type default)
			)
			(layer "F.Fab")
		)
		(fp_line
			(start 0.12065 -0.2794)
			(end 0.12065 -0.3048)
			(stroke
				(width 0.1)
				(type default)
			)
			(layer "F.Fab")
		)
		(fp_line
			(start 0.12065 -0.3048)
			(end 0.67945 -0.3048)
			(stroke
				(width 0.1)
				(type default)
			)
			(layer "F.Fab")
		)
		(fp_line
			(start 0.67945 -0.3048)
			(end 0.67945 0.3048)
			(stroke
				(width 0.1)
				(type default)
			)
			(layer "F.Fab")
		)
		(fp_line
			(start -0.67945 -0.305054)
			(end -0.12065 -0.305054)
			(stroke
				(width 0.1)
				(type default)
			)
			(layer "F.Fab")
		)
		(fp_line
			(start -0.12065 -0.305054)
			(end -0.12065 -0.2794)
			(stroke
				(width 0.1)
				(type default)
			)
			(layer "F.Fab")
		)
		(pad "1" smd circle
			(at -0.40005 0 270)
			(size 0 0)
			(layers "F.Cu" "F.Mask" "F.Paste")
			(net "USB_HOST_BMC_B_R_DN")
		)
		(pad "2" smd circle
			(at 0.40005 0 270)
			(size 0 0)
			(layers "F.Cu" "F.Mask" "F.Paste")
			(net "USB_HOST_BMC_B_DN")
		)
	)
)
